# T6G (Grand Teton) — schematic netlist excerpt (pin names and nets, part order shuffled) for the footprints in the layout excerpt that follows; sources: Cadence DE-HDL packaged netlist, KiCad conversion of 04192023_DAF0TMB3IC0_F0TG_MB_C_brd_V02_OCP.brd

R8293  Q_RES  1K 1% EMPTY  pkg 0402LF  page 193 : A = PVDD18_S5_P0 ; B = SVID_PVDDCR_CPU0_P0_SVC_R
PC438  Q_CAP  0.1UF 25V 10% X7R  pkg 0402  page 222 : A = P12V_AUX ; B = GND

(kicad_pcb
	(version 20260206)
	(generator "pcbnew")
	(generator_version "10.0")
	(general
		(thickness 1.6)
		(legacy_teardrops no)
	)
	(paper "A4")
	(title_block
		(title "04192023_DAF0TMB3IC0_F0TG_MB_C_brd_V02_OCP.brd")
		(comment 1 "Grand Teton / footprints 3465-3466 of 8354")
	)
	(layers
		(0 "F.Cu" signal "TOP")
		(4 "In1.Cu" signal "GND")
		(6 "In2.Cu" signal "IN1")
		(8 "In3.Cu" signal "GND1")
		(10 "In4.Cu" signal "IN2")
		(12 "In5.Cu" signal "GND2")
		(14 "In6.Cu" signal "IN3")
		(16 "In7.Cu" signal "GND3")
		(18 "In8.Cu" signal "VCC")
		(20 "In9.Cu" signal "VCC1")
		(22 "In10.Cu" signal "GND4")
		(24 "In11.Cu" signal "IN4")
		(26 "In12.Cu" signal "GND5")
		(28 "In13.Cu" signal "IN5")
		(30 "In14.Cu" signal "GND6")
		(32 "In15.Cu" signal "IN6")
		(34 "In16.Cu" signal "GND7")
		(2 "B.Cu" signal "BOTTOM")
		(9 "F.Adhes" user "F.Adhesive")
		(11 "B.Adhes" user "B.Adhesive")
		(13 "F.Paste" user "Package Geometry/Pastemask Top")
		(15 "B.Paste" user "Package Geometry/Pastemask Bottom")
		(5 "F.SilkS" user "Ref Des/Silkscreen Top")
		(7 "B.SilkS" user "Ref Des/Silkscreen Bottom")
		(1 "F.Mask" user "Board Geometry/Soldermask Top")
		(3 "B.Mask" user "Board Geometry/Soldermask Bottom")
		(17 "Dwgs.User" user "User.Drawings")
		(19 "Cmts.User" user "User.Comments")
		(21 "Eco1.User" user "User.Eco1")
		(23 "Eco2.User" user "User.Eco2")
		(25 "Edge.Cuts" user "Board Geometry/Outline")
		(27 "Margin" user)
		(31 "F.CrtYd" user "Package Geometry/Place Bound Top")
		(29 "B.CrtYd" user "Package Geometry/Place Bound Bottom")
		(35 "F.Fab" user "Ref Des/Assembly Top")
		(33 "B.Fab" user "Ref Des/Assembly Bottom")
	)
	(footprint ""
		(layer "F.Cu")
		(at 53.866542 -360.473498)
		(property "Reference" "PC438"
			(at 0 0 0)
			(layer "F.SilkS")
			(hide yes)
			(effects
				(font
					(size 1.27 1.27)
				)
			)
		)
		(property "Value" ""
			(at 0 0 0)
			(layer "F.Fab")
			(effects
				(font
					(size 1.27 1.27)
				)
			)
		)
		(duplicate_pad_numbers_are_jumpers no)
		(fp_line
			(start -0.7874 -0.4064)
			(end 0.7874 -0.4064)
			(stroke
				(width 0.1524)
				(type default)
			)
			(layer "F.SilkS")
		)
		(fp_line
			(start -0.7874 0.4064)
			(end -0.7874 -0.4064)
			(stroke
				(width 0.1524)
				(type default)
			)
			(layer "F.SilkS")
		)
		(fp_line
			(start 0.7874 -0.4064)
			(end 0.7874 0.4064)
			(stroke
				(width 0.1524)
				(type default)
			)
			(layer "F.SilkS")
		)
		(fp_line
			(start 0.7874 0.4064)
			(end -0.7874 0.4064)
			(stroke
				(width 0.1524)
				(type default)
			)
			(layer "F.SilkS")
		)
		(fp_line
			(start -0.67945 -0.305054)
			(end -0.12065 -0.305054)
			(stroke
				(width 0.1)
				(type default)
			)
			(layer "F.Fab")
		)
		(fp_line
			(start -0.67945 0.3048)
			(end -0.67945 -0.305054)
			(stroke
				(width 0.1)
				(type default)
			)
			(layer "F.Fab")
		)
		(fp_line
			(start -0.12065 -0.305054)
			(end -0.12065 -0.2794)
			(stroke
				(width 0.1)
				(type default)
			)
			(layer "F.Fab")
		)
		(fp_line
			(start -0.12065 -0.2794)
			(end 0.12065 -0.2794)
			(stroke
				(width 0.1)
				(type default)
			)
			(layer "F.Fab")
		)
		(fp_line
			(start -0.12065 0.2794)
			(end -0.12065 0.3048)
			(stroke
				(width 0.1)
				(type default)
			)
			(layer "F.Fab")
		)
		(fp_line
			(start -0.12065 0.3048)
			(end -0.67945 0.3048)
			(stroke
				(width 0.1)
				(type default)
			)
			(layer "F.Fab")
		)
		(fp_line
			(start 0.120396 0.2794)
			(end -0.12065 0.2794)
			(stroke
				(width 0.1)
				(type default)
			)
			(layer "F.Fab")
		)
		(fp_line
			(start 0.120396 0.3048)
			(end 0.120396 0.2794)
			(stroke
				(width 0.1)
				(type default)
			)
			(layer "F.Fab")
		)
		(fp_line
			(start 0.12065 -0.3048)
			(end 0.67945 -0.3048)
			(stroke
				(width 0.1)
				(type default)
			)
			(layer "F.Fab")
		)
		(fp_line
			(start 0.12065 -0.2794)
			(end 0.12065 -0.3048)
			(stroke
				(width 0.1)
				(type default)
			)
			(layer "F.Fab")
		)
		(fp_line
			(start 0.67945 -0.3048)
			(end 0.67945 0.3048)
			(stroke
				(width 0.1)
				(type default)
			)
			(layer "F.Fab")
		)
		(fp_line
			(start 0.67945 0.3048)
			(end 0.120396 0.3048)
			(stroke
				(width 0.1)
				(type default)
			)
			(layer "F.Fab")
		)
		(pad "1" smd circle
			(at -0.40005 0)
			(size 0 0)
			(layers "F.Cu" "F.Mask" "F.Paste")
			(net "P12V_AUX")
		)
		(pad "2" smd circle
			(at 0.40005 0)
			(size 0 0)
			(layers "F.Cu" "F.Mask" "F.Paste")
			(net "GND")
		)
	)
	(footprint ""
		(layer "F.Cu")
		(at 372.937278 -145.536158 180)
		(property "Reference" "R8293"
			(at 0 0 180)
			(layer "F.SilkS")
			(hide yes)
			(effects
				(font
					(size 1.27 1.27)
				)
			)
		)
		(property "Value" ""
			(at 0 0 180)
			(layer "F.Fab")
			(effects
				(font
					(size 1.27 1.27)
				)
			)
		)
		(duplicate_pad_numbers_are_jumpers no)
		(fp_line
			(start 0.7874 0.4064)
			(end -0.7874 0.4064)
			(stroke
				(width 0.1524)
				(type default)
			)
			(layer "F.SilkS")
		)
		(fp_line
			(start 0.7874 -0.4064)
			(end 0.7874 0.4064)
			(stroke
				(width 0.1524)
				(type default)
			)
			(layer "F.SilkS")
		)
		(fp_line
			(start -0.7874 0.4064)
			(end -0.7874 -0.4064)
			(stroke
				(width 0.1524)
				(type default)
			)
			(layer "F.SilkS")
		)
		(fp_line
			(start -0.7874 -0.4064)
			(end 0.7874 -0.4064)
			(stroke
				(width 0.1524)
				(type default)
			)
			(layer "F.SilkS")
		)
		(fp_line
			(start 0.67945 0.3048)
			(end 0.120396 0.3048)
			(stroke
				(width 0.1)
				(type default)
			)
			(layer "F.Fab")
		)
		(fp_line
			(start 0.67945 -0.3048)
			(end 0.67945 0.3048)
			(stroke
				(width 0.1)
				(type default)
			)
			(layer "F.Fab")
		)
		(fp_line
			(start 0.12065 -0.2794)
			(end 0.12065 -0.3048)
			(stroke
				(width 0.1)
				(type default)
			)
			(layer "F.Fab")
		)
		(fp_line
			(start 0.12065 -0.3048)
			(end 0.67945 -0.3048)
			(stroke
				(width 0.1)
				(type default)
			)
			(layer "F.Fab")
		)
		(fp_line
			(start 0.120396 0.3048)
			(end 0.120396 0.2794)
			(stroke
				(width 0.1)
				(type default)
			)
			(layer "F.Fab")
		)
		(fp_line
			(start 0.120396 0.2794)
			(end -0.12065 0.2794)
			(stroke
				(width 0.1)
				(type default)
			)
			(layer "F.Fab")
		)
		(fp_line
			(start -0.12065 0.3048)
			(end -0.67945 0.3048)
			(stroke
				(width 0.1)
				(type default)
			)
			(layer "F.Fab")
		)
		(fp_line
			(start -0.12065 0.2794)
			(end -0.12065 0.3048)
			(stroke
				(width 0.1)
				(type default)
			)
			(layer "F.Fab")
		)
		(fp_line
			(start -0.12065 -0.2794)
			(end 0.12065 -0.2794)
			(stroke
				(width 0.1)
				(type default)
			)
			(layer "F.Fab")
		)
		(fp_line
			(start -0.12065 -0.305054)
			(end -0.12065 -0.2794)
			(stroke
				(width 0.1)
				(type default)
			)
			(layer "F.Fab")
		)
		(fp_line
			(start -0.67945 0.3048)
			(end -0.67945 -0.305054)
			(stroke
				(width 0.1)
				(type default)
			)
			(layer "F.Fab")
		)
		(fp_line
			(start -0.67945 -0.305054)
			(end -0.12065 -0.305054)
			(stroke
				(width 0.1)
				(type default)
			)
			(layer "F.Fab")
		)
		(pad "1" smd circle
			(at -0.40005 0 180)
			(size 0 0)
			(layers "F.Cu" "F.Mask" "F.Paste")
			(net "PVDD18_S5_P0")
		)
		(pad "2" smd circle
			(at 0.40005 0 180)
			(size 0 0)
			(layers "F.Cu" "F.Mask" "F.Paste")
			(net "SVID_PVDDCR_CPU0_P0_SVC_R")
		)
	)
)
